# T6G (Grand Teton) — schematic netlist excerpt (pin names and nets, part order shuffled) for the footprints in the layout excerpt that follows; sources: Cadence DE-HDL packaged netlist, KiCad conversion of 04192023_DAF0TMB3IC0_F0TG_MB_C_brd_V02_OCP.brd

U106  PI3CSW12ZUAEX  IC  pkg UQFN10_0-5_2X1-5  page 159
  \1d+\  = I3C_1_SPD_DDRGL_CPU0_SCL
  \1d-\  = I3C_1_SPD_DDRGL_CPU0_SDA
  \2d+\  = I3C_SCM_1_R_SCL
  \2d-\  = I3C_SCM_1_R_SDA
  GND  = GND
  \oe#\  = FM_I3C_CPU0_MUX1_OE_N
  \d-\  = I3C_SPD_DDRGL_CPU0_LVC1_SDA
  \d+\  = I3C_SPD_DDRGL_CPU0_LVC1_SCL
  S  = FM_I3C_CPU0_MUX1_SEL
  VDD  = P3V3_AUX

R426  Q_RES  0 5% CHIP  pkg 0402LF  page 159 : A = I3C_0_SPD_DDRAF_CPU0_SCL ; B = I3C_0_SPD_DDRAF_CPU0_R_SCL

(kicad_pcb
	(version 20260206)
	(generator "pcbnew")
	(generator_version "10.0")
	(general
		(thickness 1.6)
		(legacy_teardrops no)
	)
	(paper "A4")
	(title_block
		(title "04192023_DAF0TMB3IC0_F0TG_MB_C_brd_V02_OCP.brd")
		(comment 1 "Grand Teton / footprints 3026-3027 of 8354")
	)
	(layers
		(0 "F.Cu" signal "TOP")
		(4 "In1.Cu" signal "GND")
		(6 "In2.Cu" signal "IN1")
		(8 "In3.Cu" signal "GND1")
		(10 "In4.Cu" signal "IN2")
		(12 "In5.Cu" signal "GND2")
		(14 "In6.Cu" signal "IN3")
		(16 "In7.Cu" signal "GND3")
		(18 "In8.Cu" signal "VCC")
		(20 "In9.Cu" signal "VCC1")
		(22 "In10.Cu" signal "GND4")
		(24 "In11.Cu" signal "IN4")
		(26 "In12.Cu" signal "GND5")
		(28 "In13.Cu" signal "IN5")
		(30 "In14.Cu" signal "GND6")
		(32 "In15.Cu" signal "IN6")
		(34 "In16.Cu" signal "GND7")
		(2 "B.Cu" signal "BOTTOM")
		(9 "F.Adhes" user "F.Adhesive")
		(11 "B.Adhes" user "B.Adhesive")
		(13 "F.Paste" user "Package Geometry/Pastemask Top")
		(15 "B.Paste" user "Package Geometry/Pastemask Bottom")
		(5 "F.SilkS" user "Ref Des/Silkscreen Top")
		(7 "B.SilkS" user "Ref Des/Silkscreen Bottom")
		(1 "F.Mask" user "Board Geometry/Soldermask Top")
		(3 "B.Mask" user "Board Geometry/Soldermask Bottom")
		(17 "Dwgs.User" user "User.Drawings")
		(19 "Cmts.User" user "User.Comments")
		(21 "Eco1.User" user "User.Eco1")
		(23 "Eco2.User" user "User.Eco2")
		(25 "Edge.Cuts" user "Board Geometry/Outline")
		(27 "Margin" user)
		(31 "F.CrtYd" user "Package Geometry/Place Bound Top")
		(29 "B.CrtYd" user "Package Geometry/Place Bound Bottom")
		(35 "F.Fab" user "Ref Des/Assembly Top")
		(33 "B.Fab" user "Ref Des/Assembly Bottom")
	)
	(footprint ""
		(layer "F.Cu")
		(at 320.981324 -192.89776 -90)
		(property "Reference" "R426"
			(at 0 0 270)
			(layer "F.SilkS")
			(hide yes)
			(effects
				(font
					(size 1.27 1.27)
				)
			)
		)
		(property "Value" ""
			(at 0 0 270)
			(layer "F.Fab")
			(effects
				(font
					(size 1.27 1.27)
				)
			)
		)
		(duplicate_pad_numbers_are_jumpers no)
		(fp_line
			(start -0.7874 0.4064)
			(end -0.7874 -0.4064)
			(stroke
				(width 0.1524)
				(type default)
			)
			(layer "F.SilkS")
		)
		(fp_line
			(start 0.7874 0.4064)
			(end -0.7874 0.4064)
			(stroke
				(width 0.1524)
				(type default)
			)
			(layer "F.SilkS")
		)
		(fp_line
			(start -0.7874 -0.4064)
			(end 0.7874 -0.4064)
			(stroke
				(width 0.1524)
				(type default)
			)
			(layer "F.SilkS")
		)
		(fp_line
			(start 0.7874 -0.4064)
			(end 0.7874 0.4064)
			(stroke
				(width 0.1524)
				(type default)
			)
			(layer "F.SilkS")
		)
		(fp_line
			(start -0.67945 0.3048)
			(end -0.67945 -0.305054)
			(stroke
				(width 0.1)
				(type default)
			)
			(layer "F.Fab")
		)
		(fp_line
			(start -0.12065 0.3048)
			(end -0.67945 0.3048)
			(stroke
				(width 0.1)
				(type default)
			)
			(layer "F.Fab")
		)
		(fp_line
			(start 0.120396 0.3048)
			(end 0.120396 0.2794)
			(stroke
				(width 0.1)
				(type default)
			)
			(layer "F.Fab")
		)
		(fp_line
			(start 0.67945 0.3048)
			(end 0.120396 0.3048)
			(stroke
				(width 0.1)
				(type default)
			)
			(layer "F.Fab")
		)
		(fp_line
			(start -0.12065 0.2794)
			(end -0.12065 0.3048)
			(stroke
				(width 0.1)
				(type default)
			)
			(layer "F.Fab")
		)
		(fp_line
			(start 0.120396 0.2794)
			(end -0.12065 0.2794)
			(stroke
				(width 0.1)
				(type default)
			)
			(layer "F.Fab")
		)
		(fp_line
			(start -0.12065 -0.2794)
			(end 0.12065 -0.2794)
			(stroke
				(width 0.1)
				(type default)
			)
			(layer "F.Fab")
		)
		(fp_line
			(start 0.12065 -0.2794)
			(end 0.12065 -0.3048)
			(stroke
				(width 0.1)
				(type default)
			)
			(layer "F.Fab")
		)
		(fp_line
			(start 0.12065 -0.3048)
			(end 0.67945 -0.3048)
			(stroke
				(width 0.1)
				(type default)
			)
			(layer "F.Fab")
		)
		(fp_line
			(start 0.67945 -0.3048)
			(end 0.67945 0.3048)
			(stroke
				(width 0.1)
				(type default)
			)
			(layer "F.Fab")
		)
		(fp_line
			(start -0.67945 -0.305054)
			(end -0.12065 -0.305054)
			(stroke
				(width 0.1)
				(type default)
			)
			(layer "F.Fab")
		)
		(fp_line
			(start -0.12065 -0.305054)
			(end -0.12065 -0.2794)
			(stroke
				(width 0.1)
				(type default)
			)
			(layer "F.Fab")
		)
		(pad "1" smd rect
			(at -0.40005 0 90)
			(size 0.4572 0.508)
			(layers "F.Cu" "F.Mask" "F.Paste")
			(net "I3C_0_SPD_DDRAF_CPU0_SCL")
		)
		(pad "2" smd rect
			(at 0.40005 0 90)
			(size 0.4572 0.508)
			(layers "F.Cu" "F.Mask" "F.Paste")
			(net "I3C_0_SPD_DDRAF_CPU0_R_SCL")
		)
	)
	(footprint ""
		(layer "F.Cu")
		(at 438.488836 -168.716452 180)
		(property "Reference" "U106"
			(at -0.808228 2.125726 0)
			(unlocked yes)
			(layer "F.SilkS")
			(effects
				(font
					(size 0.7874 0.5842)
					(thickness 0.1524)
				)
			)
		)
		(property "Value" ""
			(at 0 0 180)
			(layer "F.Fab")
			(effects
				(font
					(size 1.27 1.27)
				)
			)
		)
		(duplicate_pad_numbers_are_jumpers no)
		(fp_line
			(start 1.03378 1.284478)
			(end -1.03378 1.284478)
			(stroke
				(width 0.1524)
				(type default)
			)
			(layer "F.SilkS")
		)
		(fp_line
			(start 1.03378 -1.284478)
			(end 1.03378 1.284478)
			(stroke
				(width 0.1524)
				(type default)
			)
			(layer "F.SilkS")
		)
		(fp_line
			(start -1.03378 1.284478)
			(end -1.03378 -1.284478)
			(stroke
				(width 0.1524)
				(type default)
			)
			(layer "F.SilkS")
		)
		(fp_line
			(start -1.03378 -1.284478)
			(end 1.03378 -1.284478)
			(stroke
				(width 0.1524)
				(type default)
			)
			(layer "F.SilkS")
		)
		(fp_poly
			(pts
				(xy -1.806702 -1.052576) (xy -1.201674 -0.750062) (xy -1.806702 -0.447548)
			)
			(stroke
				(width 0)
				(type default)
			)
			(fill yes)
			(layer "F.SilkS")
		)
		(fp_line
			(start 0.774954 1.02489)
			(end -0.774954 1.02489)
			(stroke
				(width 0.1)
				(type default)
			)
			(layer "F.Fab")
		)
		(fp_line
			(start 0.774954 -1.02489)
			(end 0.774954 1.02489)
			(stroke
				(width 0.1)
				(type default)
			)
			(layer "F.Fab")
		)
		(fp_line
			(start -0.774954 1.02489)
			(end -0.774954 -1.02489)
			(stroke
				(width 0.1)
				(type default)
			)
			(layer "F.Fab")
		)
		(fp_line
			(start -0.774954 -1.02489)
			(end 0.774954 -1.02489)
			(stroke
				(width 0.1)
				(type default)
			)
			(layer "F.Fab")
		)
		(fp_poly
			(pts
				(xy -1.201674 -0.750062) (xy -1.806702 -0.447548) (xy -1.806702 -1.052576)
			)
			(stroke
				(width 0)
				(type default)
			)
			(fill yes)
			(layer "F.Fab")
		)
		(pad "1" smd rect
			(at -0.64008 -0.750062 270)
			(size 0.3048 0.5334)
			(layers "F.Cu" "F.Mask" "F.Paste")
			(net "I3C_1_SPD_DDRGL_CPU0_SCL")
		)
		(pad "2" smd rect
			(at -0.64008 -0.249936 270)
			(size 0.254 0.5334)
			(layers "F.Cu" "F.Mask" "F.Paste")
			(net "I3C_1_SPD_DDRGL_CPU0_SDA")
		)
		(pad "3" smd rect
			(at -0.64008 0.249936 270)
			(size 0.254 0.5334)
			(layers "F.Cu" "F.Mask" "F.Paste")
			(net "I3C_SCM_1_R_SCL")
		)
		(pad "4" smd rect
			(at -0.64008 0.750062 270)
			(size 0.3048 0.5334)
			(layers "F.Cu" "F.Mask" "F.Paste")
			(net "I3C_SCM_1_R_SDA")
		)
		(pad "5" smd rect
			(at 0 0.839978 180)
			(size 0.3302 0.635)
			(layers "F.Cu" "F.Mask" "F.Paste")
			(net "GND")
		)
		(pad "6" smd rect
			(at 0.64008 0.750062 270)
			(size 0.3048 0.5334)
			(layers "F.Cu" "F.Mask" "F.Paste")
			(net "FM_I3C_CPU0_MUX1_OE_N")
		)
		(pad "7" smd rect
			(at 0.64008 0.249936 270)
			(size 0.254 0.5334)
			(layers "F.Cu" "F.Mask" "F.Paste")
			(net "I3C_SPD_DDRGL_CPU0_LVC1_SDA")
		)
		(pad "8" smd rect
			(at 0.64008 -0.249936 270)
			(size 0.254 0.5334)
			(layers "F.Cu" "F.Mask" "F.Paste")
			(net "I3C_SPD_DDRGL_CPU0_LVC1_SCL")
		)
		(pad "9" smd rect
			(at 0.64008 -0.750062 270)
			(size 0.3048 0.5334)
			(layers "F.Cu" "F.Mask" "F.Paste")
			(net "FM_I3C_CPU0_MUX1_SEL")
		)
		(pad "10" smd rect
			(at 0 -0.839978 180)
			(size 0.3302 0.635)
			(layers "F.Cu" "F.Mask" "F.Paste")
			(net "P3V3_AUX")
		)
	)
)
